FILE_TYPE = CONNECTIVITY;
{Allegro Design Entry HDL 16.6-p007 (v16-6-112F) 10/10/2012}
"PAGE_NUMBER" = 254;
0"NC";
END.
